#ISCELL
  mstr_misc dns *
  *
#ISCELL
  pure_quanta quanta_title_block_c *
  *
#ISCELL
  pure_quanta_power universal_gnd *
  page170_i1
#ISCELL
  standard offpage *
  page170_i101
#ISCELL
  pure_quanta_power universal_gnd *
  page170_i102
#ISCELL
  standard offpage *
  page170_i103
#ISCELL
  standard offpage *
  page170_i104
#CELL
  pure_quanta q_cap *
  page170_i105
#ISCELL
  pure_quanta_power universal_gnd *
  page170_i106
#CELL
  pure_quanta q_cap *
  page170_i107
#CELL
  pure_quanta q_cap *
  page170_i108
#CELL
  pure_quanta q_cap *
  page170_i109
#ISCELL
  pure_quanta_power universal_gnd *
  page170_i110
#ISCELL
  pure_quanta_power universal_gnd *
  page170_i111
#CELL
  pure_quanta q_res *
  page170_i112
#CELL
  pure_quanta q_cap *
  page170_i113
#CELL
  pure_quanta q_cap *
  page170_i115
#ISCELL
  pure_quanta_power universal_gnd *
  page170_i116
#ISCELL
  pure_quanta_power universal_gnd *
  page170_i117
#CELL
  pure_quanta q_res *
  page170_i118
#CELL
  pure_quanta q_cap *
  page170_i119
#CELL
  pure_quanta isl99390frztr5935 *
  page170_i121
#CELL
  pure_quanta isl99390frztr5935 *
  page170_i122
#CELL
  pure_quanta q_cap *
  page170_i123
#CELL
  pure_quanta q_res *
  page170_i124
#ISCELL
  pure_quanta_power universal_gnd *
  page170_i125
#CELL
  pure_quanta q_cap *
  page170_i126
#CELL
  pure_quanta q_res *
  page170_i127
#ISCELL
  pure_quanta_power universal_gnd *
  page170_i128
#ISCELL
  pure_quanta_power universal_gnd *
  page170_i129
#ISCELL
  pure_quanta_power vcc_core *
  page170_i130
#ISCELL
  pure_quanta_power vcc_core *
  page170_i131
#ISCELL
  pure_quanta_power universal_gnd *
  page170_i15
#CELL
  pure_quanta q_res *
  page170_i16
#CELL
  pure_quanta q_res *
  page170_i18
#CELL
  pure_quanta q_cap *
  page170_i19
#ISCELL
  standard offpage *
  page170_i2
#CELL
  pure_quanta q_cap *
  page170_i20
#CELL
  pure_quanta q_cap *
  page170_i21
#ISCELL
  standard offpage *
  page170_i22
#CELL
  pure_quanta q_inductor4p_14 *
  page170_i23
#CELL
  pure_quanta q_cap *
  page170_i26
#ISCELL
  pure_quanta_power universal_gnd *
  page170_i27
#CELL
  pure_quanta q_cap *
  page170_i28
#ISCELL
  pure_quanta_power vcc_core *
  page170_i29
#CELL
  pure_quanta q_cap *
  page170_i3
#CELL
  pure_quanta q_cap *
  page170_i31
#ISCELL
  pure_quanta_power universal_gnd *
  page170_i32
#CELL
  pure_quanta q_cap *
  page170_i33
#ISCELL
  pure_quanta_power vcc_core *
  page170_i34
#ISCELL
  pure_quanta_power universal_gnd *
  page170_i4
#ISCELL
  standard offpage *
  page170_i5
#ISCELL
  standard offpage *
  page170_i6
#ISCELL
  standard offpage *
  page170_i7
#ISCELL
  standard offpage *
  page170_i71
#ISCELL
  standard offpage *
  page170_i73
#ISCELL
  pure_quanta_power vcc_core *
  page170_i74
#CELL
  pure_quanta q_cap *
  page170_i75
#ISCELL
  pure_quanta_power universal_gnd *
  page170_i76
#CELL
  pure_quanta q_cap *
  page170_i77
#CELL
  pure_quanta q_res *
  page170_i8
#ISCELL
  pure_quanta_power vcc_core *
  page170_i81
#CELL
  pure_quanta q_cap *
  page170_i82
#ISCELL
  pure_quanta_power universal_gnd *
  page170_i83
#CELL
  pure_quanta q_inductor4p_14 *
  page170_i84
#CELL
  pure_quanta q_cap *
  page170_i85
#CELL
  pure_quanta q_cap *
  page170_i86
#CELL
  pure_quanta q_cap *
  page170_i87
#CELL
  pure_quanta q_cap *
  page170_i88
#CELL
  pure_quanta q_res *
  page170_i89
#CELL
  pure_quanta q_res *
  page170_i90
#ISCELL
  pure_quanta_power universal_gnd *
  page170_i92
#CELL
  pure_quanta q_res *
  page170_i96
#ISCELL
  standard offpage *
  page170_i99
